# BASEBOARD_FAB2 (Tioga Pass) — schematic netlist excerpt (pin names and nets, part order shuffled) for the footprints in the layout excerpt that follows; sources: Cadence DE-HDL packaged netlist, KiCad conversion of Wiwynn_Tioga_Pass_MB.brd

C1B21  CAP  0.22UF 16V 10% X7R  pkg 0402  page 227 : A = P5V_STBY ; B = GND
C9E5  CAP_A  0.1UF 16V 10% X7R  pkg 0402V  page 139 : A = PE_PCH_SPRV_RX_DN ; B = PE_PCH_SPRV_RX_C_DN
R3D23  RES  240 1.0% EMPTY  pkg 0402  page 90 : A = PVCCIO_CPU1 ; B = PU_CPU1_TXT_AGENT

(kicad_pcb
	(version 20260206)
	(generator "pcbnew")
	(generator_version "10.0")
	(general
		(thickness 1.6)
		(legacy_teardrops no)
	)
	(paper "A4")
	(title_block
		(title "Wiwynn_Tioga_Pass_MB.brd")
		(comment 1 "Tioga Pass / footprints 1280-1282 of 4770")
	)
	(layers
		(0 "F.Cu" signal "TOP")
		(4 "In1.Cu" signal "L2GND")
		(6 "In2.Cu" signal "L3")
		(8 "In3.Cu" signal "L4GND")
		(10 "In4.Cu" signal "L5")
		(12 "In5.Cu" signal "L6GND")
		(14 "In6.Cu" signal "L7VCC")
		(16 "In7.Cu" signal "L8VCC")
		(18 "In8.Cu" signal "L9GND")
		(20 "In9.Cu" signal "L10")
		(22 "In10.Cu" signal "L11GND")
		(24 "In11.Cu" signal "L12")
		(26 "In12.Cu" signal "L13GND")
		(2 "B.Cu" signal "BOTTOM")
		(9 "F.Adhes" user "F.Adhesive")
		(11 "B.Adhes" user "B.Adhesive")
		(13 "F.Paste" user "Package Geometry/Pastemask Top")
		(15 "B.Paste" user "Package Geometry/Pastemask Bottom")
		(5 "F.SilkS" user "Ref Des/Silkscreen Top")
		(7 "B.SilkS" user "Ref Des/Silkscreen Bottom")
		(1 "F.Mask" user "Board Geometry/Soldermask Top")
		(3 "B.Mask" user "Board Geometry/Soldermask Bottom")
		(17 "Dwgs.User" user "User.Drawings")
		(19 "Cmts.User" user "User.Comments")
		(21 "Eco1.User" user "User.Eco1")
		(23 "Eco2.User" user "User.Eco2")
		(25 "Edge.Cuts" user "Board Geometry/Outline")
		(27 "Margin" user)
		(31 "F.CrtYd" user "Package Geometry/Place Bound Top")
		(29 "B.CrtYd" user "Package Geometry/Place Bound Bottom")
		(35 "F.Fab" user "Ref Des/Assembly Top")
		(33 "B.Fab" user "Ref Des/Assembly Bottom")
	)
	(footprint ""
		(layer "F.Cu")
		(at 110.744 -69.85)
		(property "Reference" "R3D23"
			(at 0 0 0)
			(layer "F.SilkS")
			(hide yes)
			(effects
				(font
					(size 1.27 1.27)
				)
			)
		)
		(property "Value" ""
			(at 0 0 0)
			(layer "F.Fab")
			(effects
				(font
					(size 1.27 1.27)
				)
			)
		)
		(duplicate_pad_numbers_are_jumpers no)
		(fp_poly
			(pts
				(xy -0.2794 -0.1016) (xy 0.2794 -0.1016) (xy 0.2794 0.9906) (xy -0.2794 0.9906)
			)
			(stroke
				(width 0)
				(type default)
			)
			(fill no)
			(layer "F.CrtYd")
		)
		(fp_line
			(start -0.2794 -0.1016)
			(end -0.2794 0.9906)
			(stroke
				(width 0.1)
				(type default)
			)
			(layer "F.Fab")
		)
		(fp_line
			(start -0.2794 0.9906)
			(end 0.2794 0.9906)
			(stroke
				(width 0.1)
				(type default)
			)
			(layer "F.Fab")
		)
		(fp_line
			(start 0.2794 -0.1016)
			(end -0.2794 -0.1016)
			(stroke
				(width 0.1)
				(type default)
			)
			(layer "F.Fab")
		)
		(fp_line
			(start 0.2794 0.9906)
			(end 0.2794 -0.1016)
			(stroke
				(width 0.1)
				(type default)
			)
			(layer "F.Fab")
		)
		(pad "1" smd rect
			(at 0 0)
			(size 0.508 0.508)
			(layers "F.Cu" "F.Mask" "F.Paste")
			(net "PVCCIO_CPU1")
		)
		(pad "2" smd rect
			(at 0 0.889)
			(size 0.508 0.508)
			(layers "F.Cu" "F.Mask" "F.Paste")
			(net "PU_CPU1_TXT_AGENT")
		)
		(zone
			(layer "F.Cu")
			(hatch none 0.5)
			(connect_pads
				(clearance 0)
			)
			(min_thickness 0.25)
			(keepout
				(tracks allowed)
				(vias not_allowed)
				(pads allowed)
				(copperpour not_allowed)
				(footprints allowed)
			)
			(placement
				(enabled no)
				(sheetname "")
			)
			(fill
				(thermal_gap 0.5)
				(thermal_bridge_width 0.5)
				(island_removal_mode 0)
			)
			(polygon
				(pts
					(xy 110.49 -69.596) (xy 110.998 -69.596) (xy 110.998 -69.215) (xy 110.49 -69.215)
				)
			)
		)
		(zone
			(layer "F.Cu")
			(hatch none 0.5)
			(connect_pads
				(clearance 0)
			)
			(min_thickness 0.25)
			(keepout
				(tracks not_allowed)
				(vias allowed)
				(pads allowed)
				(copperpour not_allowed)
				(footprints allowed)
			)
			(placement
				(enabled no)
				(sheetname "")
			)
			(fill
				(thermal_gap 0.5)
				(thermal_bridge_width 0.5)
				(island_removal_mode 0)
			)
			(polygon
				(pts
					(xy 110.49 -69.215) (xy 110.998 -69.215) (xy 110.998 -69.596) (xy 110.49 -69.596)
				)
			)
		)
	)
	(footprint ""
		(layer "F.Cu")
		(at 486.3846 -50.2539 180)
		(property "Reference" "C9E5"
			(at 0 0 180)
			(layer "F.SilkS")
			(hide yes)
			(effects
				(font
					(size 1.27 1.27)
				)
			)
		)
		(property "Value" ""
			(at 0 0 180)
			(layer "F.Fab")
			(effects
				(font
					(size 1.27 1.27)
				)
			)
		)
		(duplicate_pad_numbers_are_jumpers no)
		(fp_poly
			(pts
				(xy 0.3048 -0.1016) (xy 0.3048 0.9906) (xy -0.3048 0.9906) (xy -0.3048 -0.1016)
			)
			(stroke
				(width 0)
				(type default)
			)
			(fill no)
			(layer "F.CrtYd")
		)
		(fp_line
			(start 0.3048 0.9906)
			(end 0.3048 -0.1016)
			(stroke
				(width 0.1)
				(type default)
			)
			(layer "F.Fab")
		)
		(fp_line
			(start 0.3048 -0.1016)
			(end -0.3048 -0.1016)
			(stroke
				(width 0.1)
				(type default)
			)
			(layer "F.Fab")
		)
		(fp_line
			(start -0.3048 0.9906)
			(end 0.3048 0.9906)
			(stroke
				(width 0.1)
				(type default)
			)
			(layer "F.Fab")
		)
		(fp_line
			(start -0.3048 -0.1016)
			(end -0.3048 0.9906)
			(stroke
				(width 0.1)
				(type default)
			)
			(layer "F.Fab")
		)
		(pad "1" smd rect
			(at 0 0 180)
			(size 0.508 0.508)
			(layers "F.Cu" "F.Mask" "F.Paste")
			(net "PE_PCH_SPRV_RX_DN")
		)
		(pad "2" smd rect
			(at 0 0.889 180)
			(size 0.508 0.508)
			(layers "F.Cu" "F.Mask" "F.Paste")
			(net "PE_PCH_SPRV_RX_C_DN")
		)
		(zone
			(layer "F.Cu")
			(hatch none 0.5)
			(connect_pads
				(clearance 0)
			)
			(min_thickness 0.25)
			(keepout
				(tracks not_allowed)
				(vias allowed)
				(pads allowed)
				(copperpour not_allowed)
				(footprints allowed)
			)
			(placement
				(enabled no)
				(sheetname "")
			)
			(fill
				(thermal_gap 0.5)
				(thermal_bridge_width 0.5)
				(island_removal_mode 0)
			)
			(polygon
				(pts
					(xy 486.6386 -50.8889) (xy 486.1306 -50.8889) (xy 486.1306 -50.5079) (xy 486.6386 -50.5079)
				)
			)
		)
		(zone
			(layer "F.Cu")
			(hatch none 0.5)
			(connect_pads
				(clearance 0)
			)
			(min_thickness 0.25)
			(keepout
				(tracks allowed)
				(vias not_allowed)
				(pads allowed)
				(copperpour not_allowed)
				(footprints allowed)
			)
			(placement
				(enabled no)
				(sheetname "")
			)
			(fill
				(thermal_gap 0.5)
				(thermal_bridge_width 0.5)
				(island_removal_mode 0)
			)
			(polygon
				(pts
					(xy 486.6386 -50.5079) (xy 486.1306 -50.5079) (xy 486.1306 -50.8889) (xy 486.6386 -50.8889)
				)
			)
		)
	)
	(footprint ""
		(layer "F.Cu")
		(at 1.7018 -134.3152 90)
		(property "Reference" "C1B21"
			(at 0 0 90)
			(layer "F.SilkS")
			(hide yes)
			(effects
				(font
					(size 1.27 1.27)
				)
			)
		)
		(property "Value" ""
			(at 0 0 90)
			(layer "F.Fab")
			(effects
				(font
					(size 1.27 1.27)
				)
			)
		)
		(duplicate_pad_numbers_are_jumpers no)
		(fp_rect
			(start 0.3048 0.9906)
			(end -0.3048 -0.1016)
			(stroke
				(width 0)
				(type default)
			)
			(fill no)
			(layer "F.CrtYd")
		)
		(fp_line
			(start 0.3048 -0.1016)
			(end -0.3048 -0.1016)
			(stroke
				(width 0.1)
				(type default)
			)
			(layer "F.Fab")
		)
		(fp_line
			(start -0.3048 -0.1016)
			(end -0.3048 0.9906)
			(stroke
				(width 0.1)
				(type default)
			)
			(layer "F.Fab")
		)
		(fp_line
			(start 0.3048 0.9906)
			(end 0.3048 -0.1016)
			(stroke
				(width 0.1)
				(type default)
			)
			(layer "F.Fab")
		)
		(fp_line
			(start -0.3048 0.9906)
			(end 0.3048 0.9906)
			(stroke
				(width 0.1)
				(type default)
			)
			(layer "F.Fab")
		)
		(pad "1" smd rect
			(at 0 0 90)
			(size 0.508 0.508)
			(layers "F.Cu" "F.Mask" "F.Paste")
			(net "P5V_STBY")
		)
		(pad "2" smd rect
			(at 0 0.889 90)
			(size 0.508 0.508)
			(layers "F.Cu" "F.Mask" "F.Paste")
			(net "GND")
		)
		(zone
			(layer "F.Cu")
			(hatch none 0.5)
			(connect_pads
				(clearance 0)
			)
			(min_thickness 0.25)
			(keepout
				(tracks not_allowed)
				(vias allowed)
				(pads allowed)
				(copperpour not_allowed)
				(footprints allowed)
			)
			(placement
				(enabled no)
				(sheetname "")
			)
			(fill
				(thermal_gap 0.5)
				(thermal_bridge_width 0.5)
				(island_removal_mode 0)
			)
			(polygon
				(pts
					(xy 2.3368 -134.5692) (xy 1.9558 -134.5692) (xy 1.9558 -134.0612) (xy 2.3368 -134.0612)
				)
			)
		)
		(zone
			(layer "F.Cu")
			(hatch none 0.5)
			(connect_pads
				(clearance 0)
			)
			(min_thickness 0.25)
			(keepout
				(tracks allowed)
				(vias not_allowed)
				(pads allowed)
				(copperpour not_allowed)
				(footprints allowed)
			)
			(placement
				(enabled no)
				(sheetname "")
			)
			(fill
				(thermal_gap 0.5)
				(thermal_bridge_width 0.5)
				(island_removal_mode 0)
			)
			(polygon
				(pts
					(xy 2.3368 -134.5692) (xy 1.9558 -134.5692) (xy 1.9558 -134.0612) (xy 2.3368 -134.0612)
				)
			)
		)
	)
)
